(kicad_pcb
	(version 20221018)
	(generator pcbnew)
	(general
    (thickness 1.7403)
  )
	(paper "A4")
	(title_block
    (title "Data Center RDIMM DDR4 Tester")
    (date "2024-09-30")
    (rev "1.2.4")
		(comment 9 "footprints 204-213 of 690")
	)
	(layers
    (0 "F.Cu" signal)
    (1 "In1.Cu" power)
    (2 "In2.Cu" signal)
    (3 "In3.Cu" power)
    (4 "In4.Cu" power)
    (5 "In5.Cu" signal)
    (6 "In6.Cu" power)
    (7 "In7.Cu" signal)
    (8 "In8.Cu" power)
    (9 "In9.Cu" signal)
    (10 "In10.Cu" power)
    (31 "B.Cu" signal)
    (32 "B.Adhes" user "B.Adhesive")
    (33 "F.Adhes" user "F.Adhesive")
    (34 "B.Paste" user)
    (35 "F.Paste" user)
    (36 "B.SilkS" user "B.Silkscreen")
    (37 "F.SilkS" user "F.Silkscreen")
    (38 "B.Mask" user)
    (39 "F.Mask" user)
    (40 "Dwgs.User" user "User.Drawings")
    (41 "Cmts.User" user "User.Comments")
    (42 "Eco1.User" user "User.Eco1")
    (43 "Eco2.User" user "User.Eco2")
    (44 "Edge.Cuts" user)
    (45 "Margin" user)
    (46 "B.CrtYd" user "B.Courtyard")
    (47 "F.CrtYd" user "F.Courtyard")
    (48 "B.Fab" user)
    (49 "F.Fab" user)
  )
	(footprint "data-center-rdimm-ddr4-tester-footprints:C_0603_1608Metric" (layer "F.Cu")
    (at 125.415171 102.893829 90)
    (descr "Capacitor SMD 0603")
    (tags "capacitor 0603")
    (property "Author" "Antmicro")
    (property "Dielectric" "")
    (property "License" "Apache-2.0")
    (property "MPN" "GRM188R60J476ME15D")
    (property "Manufacturer" "Murata")
    (property "Sheetfile" "supply.kicad_sch")
    (property "Sheetname" "Supply")
    (property "Val" "47u")
    (property "Voltage" "")
    (property "ki_description" " ")
    (attr smd)
    (fp_text reference "C180" (at -1.276171 3.754829 90) (layer "F.SilkS")
        (effects (font (size 0.7 0.7) (thickness 0.15)) (justify left bottom))
    )
    (fp_text value "C_47u_0603" (at 0 1.6 90) (layer "F.Fab") hide
        (effects (font (size 0.7 0.7) (thickness 0.15)) (justify left bottom))
    )
    (fp_text user "License: Apache-2.0" (at -1.682 5.895 90) (layer "F.Fab") hide
        (effects (font (size 0.7 0.7) (thickness 0.15)) (justify left bottom))
    )
    (fp_text user "Author: Antmicro" (at -1.682 4.894 90) (layer "F.Fab") hide
        (effects (font (size 0.7 0.7) (thickness 0.15)) (justify left bottom))
    )
    (fp_text user "${REFERENCE}" (at -1.682 3.895 90) (layer "F.Fab") hide
        (effects (font (size 0.7 0.7) (thickness 0.15)) (justify left bottom))
    )
    (fp_line (start -0.3 -0.3) (end 0.3 -0.3)
      (stroke (width 0.15) (type solid)) (layer "F.SilkS"))
    (fp_line (start -0.3 0.3) (end 0.3 0.3)
      (stroke (width 0.15) (type solid)) (layer "F.SilkS"))
    (fp_rect (start -1.24 -0.7) (end 1.24 0.7)
      (stroke (width 0.05) (type solid)) (fill none) (layer "F.CrtYd"))
    (fp_rect (start -0.8 -0.4) (end 0.8 0.4)
      (stroke (width 0.15) (type solid)) (fill none) (layer "F.Fab"))
    (pad "1" smd roundrect (at -0.7 0 90) (size 0.6 0.8) (layers "F.Cu" "F.Paste" "F.Mask") (roundrect_rratio 0.2)
      (net 104 "VCC5V0") (pintype "passive"))
    (pad "2" smd roundrect (at 0.7 0 90) (size 0.6 0.8) (layers "F.Cu" "F.Paste" "F.Mask") (roundrect_rratio 0.2)
      (net 9 "GND") (pintype "passive"))
  )
	(footprint "data-center-rdimm-ddr4-tester-footprints:C_0603_1608Metric" (layer "F.Cu")
    (at 126.915171 102.893829 90)
    (descr "Capacitor SMD 0603")
    (tags "capacitor 0603")
    (property "Author" "Antmicro")
    (property "Dielectric" "")
    (property "License" "Apache-2.0")
    (property "MPN" "GRM188R60J476ME15D")
    (property "Manufacturer" "Murata")
    (property "Sheetfile" "supply.kicad_sch")
    (property "Sheetname" "Supply")
    (property "Val" "47u")
    (property "Voltage" "")
    (property "ki_description" " ")
    (attr smd)
    (fp_text reference "C182" (at -1.286171 3.184829 90) (layer "F.SilkS")
        (effects (font (size 0.7 0.7) (thickness 0.15)) (justify left bottom))
    )
    (fp_text value "C_47u_0603" (at 0 1.6 90) (layer "F.Fab") hide
        (effects (font (size 0.7 0.7) (thickness 0.15)) (justify left bottom))
    )
    (fp_text user "License: Apache-2.0" (at -1.682 5.895 90) (layer "F.Fab") hide
        (effects (font (size 0.7 0.7) (thickness 0.15)) (justify left bottom))
    )
    (fp_text user "${REFERENCE}" (at -1.682 3.895 90) (layer "F.Fab") hide
        (effects (font (size 0.7 0.7) (thickness 0.15)) (justify left bottom))
    )
    (fp_text user "Author: Antmicro" (at -1.682 4.894 90) (layer "F.Fab") hide
        (effects (font (size 0.7 0.7) (thickness 0.15)) (justify left bottom))
    )
    (fp_line (start -0.3 -0.3) (end 0.3 -0.3)
      (stroke (width 0.15) (type solid)) (layer "F.SilkS"))
    (fp_line (start -0.3 0.3) (end 0.3 0.3)
      (stroke (width 0.15) (type solid)) (layer "F.SilkS"))
    (fp_rect (start -1.24 -0.7) (end 1.24 0.7)
      (stroke (width 0.05) (type solid)) (fill none) (layer "F.CrtYd"))
    (fp_rect (start -0.8 -0.4) (end 0.8 0.4)
      (stroke (width 0.15) (type solid)) (fill none) (layer "F.Fab"))
    (pad "1" smd roundrect (at -0.7 0 90) (size 0.6 0.8) (layers "F.Cu" "F.Paste" "F.Mask") (roundrect_rratio 0.2)
      (net 104 "VCC5V0") (pintype "passive"))
    (pad "2" smd roundrect (at 0.7 0 90) (size 0.6 0.8) (layers "F.Cu" "F.Paste" "F.Mask") (roundrect_rratio 0.2)
      (net 9 "GND") (pintype "passive"))
  )
	(footprint "data-center-rdimm-ddr4-tester-footprints:R_0402_1005Metric" (layer "F.Cu")
    (at 124.326328 105.405008 -90)
    (descr "Resistor SMD 0402")
    (tags "resistor SMD 0402")
    (property "Author" "Antmicro")
    (property "License" "Apache-2.0")
    (property "MPN" "CR0402-FX-1002GLF")
    (property "Manufacturer" "Bourns")
    (property "Sheetfile" "supply.kicad_sch")
    (property "Sheetname" "Supply")
    (property "Tolerance" "1%")
    (property "Val" "10k")
    (property "ki_description" "10k resistor in 0402 package with 1% tolerance")
    (attr smd)
    (fp_text reference "R82" (at 0.534992 -2.263672 -90) (layer "F.SilkS")
        (effects (font (size 0.7 0.7) (thickness 0.15)) (justify left bottom))
    )
    (fp_text value "R_10k_0402" (at 0 1.4 -90) (layer "F.Fab") hide
        (effects (font (size 0.7 0.7) (thickness 0.15)) (justify left bottom))
    )
    (fp_text user "License: Apache-2.0" (at -0.95 5.169 -90) (layer "F.Fab") hide
        (effects (font (size 0.7 0.7) (thickness 0.15)) (justify left bottom))
    )
    (fp_text user "${REFERENCE}" (at -0.95 3.168 -90) (layer "F.Fab") hide
        (effects (font (size 0.7 0.7) (thickness 0.15)) (justify left bottom))
    )
    (fp_text user "Author: Antmicro" (at -0.95 4.169 -90) (layer "F.Fab") hide
        (effects (font (size 0.7 0.7) (thickness 0.15)) (justify left bottom))
    )
    (fp_rect (start -0.93 -0.47) (end 0.93 0.47)
      (stroke (width 0.05) (type solid)) (fill none) (layer "F.CrtYd"))
    (fp_rect (start -0.5 -0.25) (end 0.5 0.25)
      (stroke (width 0.15) (type solid)) (fill none) (layer "F.Fab"))
    (pad "1" smd roundrect (at -0.485 0 270) (size 0.59 0.64) (layers "F.Cu" "F.Paste" "F.Mask") (roundrect_rratio 0.25)
      (net 644 "Net-(U9-FB)") (pintype "passive"))
    (pad "2" smd roundrect (at 0.485 0 270) (size 0.59 0.64) (layers "F.Cu" "F.Paste" "F.Mask") (roundrect_rratio 0.25)
      (net 9 "GND") (pintype "passive"))
  )
	(footprint "data-center-rdimm-ddr4-tester-footprints:C_0402_1005Metric" (layer "F.Cu")
    (at 114.166328 110.620008 180)
    (descr "Capacitor SMD 0402")
    (tags "capacitor SMD 0402")
    (property "Author" "Antmicro")
    (property "Dielectric" "")
    (property "License" "Apache-2.0")
    (property "MPN" "C1005X6S1A105K050BC")
    (property "Manufacturer" "TDK")
    (property "Sheetfile" "supply.kicad_sch")
    (property "Sheetname" "Supply")
    (property "Val" "1u")
    (property "Voltage" "")
    (property "ki_description" " ")
    (attr smd)
    (fp_text reference "C220" (at -2.133672 -1.879992 180) (layer "F.SilkS")
        (effects (font (size 0.7 0.7) (thickness 0.15)) (justify left bottom))
    )
    (fp_text value "C_1u_0402" (at 0 1.4 180) (layer "F.Fab") hide
        (effects (font (size 0.7 0.7) (thickness 0.15)) (justify left bottom))
    )
    (fp_text user "License: Apache-2.0" (at -0.932 5.17 180) (layer "F.Fab") hide
        (effects (font (size 0.7 0.7) (thickness 0.15)) (justify left bottom))
    )
    (fp_text user "Author: Antmicro" (at -0.932 4.17 180) (layer "F.Fab") hide
        (effects (font (size 0.7 0.7) (thickness 0.15)) (justify left bottom))
    )
    (fp_text user "${REFERENCE}" (at -0.932 3.168 180) (layer "F.Fab") hide
        (effects (font (size 0.7 0.7) (thickness 0.15)) (justify left bottom))
    )
    (fp_rect (start -0.94 -0.47) (end 0.94 0.47)
      (stroke (width 0.05) (type solid)) (fill none) (layer "F.CrtYd"))
    (fp_rect (start -0.499 -0.249) (end 0.499 0.249)
      (stroke (width 0.15) (type solid)) (fill none) (layer "F.Fab"))
    (pad "1" smd roundrect (at -0.484 0 180) (size 0.59 0.64) (layers "F.Cu" "F.Paste" "F.Mask") (roundrect_rratio 0.25)
      (net 304 "VCC3V3") (pintype "passive"))
    (pad "2" smd roundrect (at 0.484 0 180) (size 0.59 0.64) (layers "F.Cu" "F.Paste" "F.Mask") (roundrect_rratio 0.25)
      (net 9 "GND") (pintype "passive"))
  )
	(footprint "data-center-rdimm-ddr4-tester-footprints:C_0402_1005Metric" (layer "F.Cu")
    (at 142.036328 86.410008)
    (descr "Capacitor SMD 0402")
    (tags "capacitor SMD 0402")
    (property "Author" "Antmicro")
    (property "Dielectric" "")
    (property "License" "Apache-2.0")
    (property "MPN" "C1005X6S1A105K050BC")
    (property "Manufacturer" "TDK")
    (property "Sheetfile" "supply.kicad_sch")
    (property "Sheetname" "Supply")
    (property "Val" "1u")
    (property "Voltage" "")
    (property "ki_description" " ")
    (attr smd)
    (fp_text reference "C98" (at 0.773672 1.109992) (layer "F.SilkS")
        (effects (font (size 0.7 0.7) (thickness 0.15)) (justify left bottom))
    )
    (fp_text value "C_1u_0402" (at 0 1.4) (layer "F.Fab") hide
        (effects (font (size 0.7 0.7) (thickness 0.15)) (justify left bottom))
    )
    (fp_text user "Author: Antmicro" (at -0.932 4.17) (layer "F.Fab") hide
        (effects (font (size 0.7 0.7) (thickness 0.15)) (justify left bottom))
    )
    (fp_text user "License: Apache-2.0" (at -0.932 5.17) (layer "F.Fab") hide
        (effects (font (size 0.7 0.7) (thickness 0.15)) (justify left bottom))
    )
    (fp_text user "${REFERENCE}" (at -0.932 3.168) (layer "F.Fab") hide
        (effects (font (size 0.7 0.7) (thickness 0.15)) (justify left bottom))
    )
    (fp_rect (start -0.94 -0.47) (end 0.94 0.47)
      (stroke (width 0.05) (type solid)) (fill none) (layer "F.CrtYd"))
    (fp_rect (start -0.499 -0.249) (end 0.499 0.249)
      (stroke (width 0.15) (type solid)) (fill none) (layer "F.Fab"))
    (pad "1" smd roundrect (at -0.484 0) (size 0.59 0.64) (layers "F.Cu" "F.Paste" "F.Mask") (roundrect_rratio 0.25)
      (net 300 "VCC1V0") (pintype "passive"))
    (pad "2" smd roundrect (at 0.484 0) (size 0.59 0.64) (layers "F.Cu" "F.Paste" "F.Mask") (roundrect_rratio 0.25)
      (net 9 "GND") (pintype "passive"))
  )
	(footprint "data-center-rdimm-ddr4-tester-footprints:C_0402_1005Metric" (layer "F.Cu")
    (at 135.786328 89.585008 90)
    (descr "Capacitor SMD 0402")
    (tags "capacitor SMD 0402")
    (property "Author" "Antmicro")
    (property "Dielectric" "")
    (property "License" "Apache-2.0")
    (property "MPN" "CC0402MRX5R5BB106")
    (property "Manufacturer" "Yaego")
    (property "Sheetfile" "supply.kicad_sch")
    (property "Sheetname" "Supply")
    (property "Val" "10u")
    (property "Voltage" "")
    (property "ki_description" " ")
    (attr smd)
    (fp_text reference "C45" (at 0.825008 0.173672 90) (layer "F.SilkS")
        (effects (font (size 0.7 0.7) (thickness 0.15)) (justify left bottom))
    )
    (fp_text value "C_10u_0402" (at 0 1.4 90) (layer "F.Fab") hide
        (effects (font (size 0.7 0.7) (thickness 0.15)) (justify left bottom))
    )
    (fp_text user "License: Apache-2.0" (at -0.932 5.17 90) (layer "F.Fab") hide
        (effects (font (size 0.7 0.7) (thickness 0.15)) (justify left bottom))
    )
    (fp_text user "${REFERENCE}" (at -0.932 3.168 90) (layer "F.Fab") hide
        (effects (font (size 0.7 0.7) (thickness 0.15)) (justify left bottom))
    )
    (fp_text user "Author: Antmicro" (at -0.932 4.17 90) (layer "F.Fab") hide
        (effects (font (size 0.7 0.7) (thickness 0.15)) (justify left bottom))
    )
    (fp_rect (start -0.94 -0.47) (end 0.94 0.47)
      (stroke (width 0.05) (type solid)) (fill none) (layer "F.CrtYd"))
    (fp_rect (start -0.499 -0.249) (end 0.499 0.249)
      (stroke (width 0.15) (type solid)) (fill none) (layer "F.Fab"))
    (pad "1" smd roundrect (at -0.484 0 90) (size 0.59 0.64) (layers "F.Cu" "F.Paste" "F.Mask") (roundrect_rratio 0.25)
      (net 307 "5V0_SYS") (pintype "passive"))
    (pad "2" smd roundrect (at 0.484 0 90) (size 0.59 0.64) (layers "F.Cu" "F.Paste" "F.Mask") (roundrect_rratio 0.25)
      (net 9 "GND") (pintype "passive"))
  )
	(footprint "data-center-rdimm-ddr4-tester-footprints:C_0402_1005Metric" (layer "F.Cu")
    (at 140.936328 88.125008 90)
    (descr "Capacitor SMD 0402")
    (tags "capacitor SMD 0402")
    (property "Author" "Antmicro")
    (property "Dielectric" "X5R")
    (property "License" "Apache-2.0")
    (property "MPN" "GRM155R61H104KE14D")
    (property "Manufacturer" "Murata")
    (property "Sheetfile" "supply.kicad_sch")
    (property "Sheetname" "Supply")
    (property "Val" "100n")
    (property "Voltage" "50V")
    (property "ki_description" " ")
    (attr smd)
    (fp_text reference "C46" (at -1.094992 1.183672 90) (layer "F.SilkS")
        (effects (font (size 0.7 0.7) (thickness 0.15)) (justify left bottom))
    )
    (fp_text value "C_100n_0402" (at 0 1.4 90) (layer "F.Fab") hide
        (effects (font (size 0.7 0.7) (thickness 0.15)) (justify left bottom))
    )
    (fp_text user "Author: Antmicro" (at -0.932 4.17 90) (layer "F.Fab") hide
        (effects (font (size 0.7 0.7) (thickness 0.15)) (justify left bottom))
    )
    (fp_text user "License: Apache-2.0" (at -0.932 5.17 90) (layer "F.Fab") hide
        (effects (font (size 0.7 0.7) (thickness 0.15)) (justify left bottom))
    )
    (fp_text user "${REFERENCE}" (at -0.932 3.168 90) (layer "F.Fab") hide
        (effects (font (size 0.7 0.7) (thickness 0.15)) (justify left bottom))
    )
    (fp_rect (start -0.94 -0.47) (end 0.94 0.47)
      (stroke (width 0.05) (type solid)) (fill none) (layer "F.CrtYd"))
    (fp_rect (start -0.499 -0.249) (end 0.499 0.249)
      (stroke (width 0.15) (type solid)) (fill none) (layer "F.Fab"))
    (pad "1" smd roundrect (at -0.484 0 90) (size 0.59 0.64) (layers "F.Cu" "F.Paste" "F.Mask") (roundrect_rratio 0.25)
      (net 2 "Net-(U4-BST)") (pintype "passive"))
    (pad "2" smd roundrect (at 0.484 0 90) (size 0.59 0.64) (layers "F.Cu" "F.Paste" "F.Mask") (roundrect_rratio 0.25)
      (net 3 "Net-(U4-SW)") (pintype "passive"))
  )
	(footprint "data-center-rdimm-ddr4-tester-footprints:C_0402_1005Metric" (layer "F.Cu")
    (at 142.036328 85.410008)
    (descr "Capacitor SMD 0402")
    (tags "capacitor SMD 0402")
    (property "Author" "Antmicro")
    (property "Dielectric" "")
    (property "License" "Apache-2.0")
    (property "MPN" "04024W226MAT2A")
    (property "Manufacturer" "AVX")
    (property "Sheetfile" "supply.kicad_sch")
    (property "Sheetname" "Supply")
    (property "Val" "22u")
    (property "Voltage" "")
    (property "ki_description" " ")
    (attr smd)
    (fp_text reference "C97" (at 0.773672 1.109992) (layer "F.SilkS")
        (effects (font (size 0.7 0.7) (thickness 0.15)) (justify left bottom))
    )
    (fp_text value "C_22u_0402" (at 0 1.4) (layer "F.Fab") hide
        (effects (font (size 0.7 0.7) (thickness 0.15)) (justify left bottom))
    )
    (fp_text user "${REFERENCE}" (at -0.932 3.168) (layer "F.Fab") hide
        (effects (font (size 0.7 0.7) (thickness 0.15)) (justify left bottom))
    )
    (fp_text user "License: Apache-2.0" (at -0.932 5.17) (layer "F.Fab") hide
        (effects (font (size 0.7 0.7) (thickness 0.15)) (justify left bottom))
    )
    (fp_text user "Author: Antmicro" (at -0.932 4.17) (layer "F.Fab") hide
        (effects (font (size 0.7 0.7) (thickness 0.15)) (justify left bottom))
    )
    (fp_rect (start -0.94 -0.47) (end 0.94 0.47)
      (stroke (width 0.05) (type solid)) (fill none) (layer "F.CrtYd"))
    (fp_rect (start -0.499 -0.249) (end 0.499 0.249)
      (stroke (width 0.15) (type solid)) (fill none) (layer "F.Fab"))
    (pad "1" smd roundrect (at -0.484 0) (size 0.59 0.64) (layers "F.Cu" "F.Paste" "F.Mask") (roundrect_rratio 0.25)
      (net 300 "VCC1V0") (pintype "passive"))
    (pad "2" smd roundrect (at 0.484 0) (size 0.59 0.64) (layers "F.Cu" "F.Paste" "F.Mask") (roundrect_rratio 0.25)
      (net 9 "GND") (pintype "passive"))
  )
	(footprint "data-center-rdimm-ddr4-tester-footprints:C_0402_1005Metric" (layer "F.Cu")
    (at 155.324328 118.127008)
    (descr "Capacitor SMD 0402")
    (tags "capacitor SMD 0402")
    (property "Author" "Antmicro")
    (property "Dielectric" "")
    (property "License" "Apache-2.0")
    (property "MPN" "CC0402MRX5R5BB106")
    (property "Manufacturer" "Yaego")
    (property "Sheetfile" "supply.kicad_sch")
    (property "Sheetname" "Supply")
    (property "Val" "10u")
    (property "Voltage" "")
    (property "ki_description" " ")
    (attr smd)
    (fp_text reference "C99" (at -1.014328 -0.547008) (layer "F.SilkS")
        (effects (font (size 0.7 0.7) (thickness 0.15)) (justify left bottom))
    )
    (fp_text value "C_10u_0402" (at 0 1.4) (layer "F.Fab") hide
        (effects (font (size 0.7 0.7) (thickness 0.15)) (justify left bottom))
    )
    (fp_text user "License: Apache-2.0" (at -0.932 5.17) (layer "F.Fab") hide
        (effects (font (size 0.7 0.7) (thickness 0.15)) (justify left bottom))
    )
    (fp_text user "${REFERENCE}" (at -0.932 3.168) (layer "F.Fab") hide
        (effects (font (size 0.7 0.7) (thickness 0.15)) (justify left bottom))
    )
    (fp_text user "Author: Antmicro" (at -0.932 4.17) (layer "F.Fab") hide
        (effects (font (size 0.7 0.7) (thickness 0.15)) (justify left bottom))
    )
    (fp_rect (start -0.94 -0.47) (end 0.94 0.47)
      (stroke (width 0.05) (type solid)) (fill none) (layer "F.CrtYd"))
    (fp_rect (start -0.499 -0.249) (end 0.499 0.249)
      (stroke (width 0.15) (type solid)) (fill none) (layer "F.Fab"))
    (pad "1" smd roundrect (at -0.484 0) (size 0.59 0.64) (layers "F.Cu" "F.Paste" "F.Mask") (roundrect_rratio 0.25)
      (net 307 "5V0_SYS") (pintype "passive"))
    (pad "2" smd roundrect (at 0.484 0) (size 0.59 0.64) (layers "F.Cu" "F.Paste" "F.Mask") (roundrect_rratio 0.25)
      (net 9 "GND") (pintype "passive"))
  )
	(footprint "data-center-rdimm-ddr4-tester-footprints:C_0402_1005Metric" (layer "F.Cu")
    (at 151.599328 114.552008 180)
    (descr "Capacitor SMD 0402")
    (tags "capacitor SMD 0402")
    (property "Author" "Antmicro")
    (property "Dielectric" "X5R")
    (property "License" "Apache-2.0")
    (property "MPN" "GRM155R61H104KE14D")
    (property "Manufacturer" "Murata")
    (property "Sheetfile" "supply.kicad_sch")
    (property "Sheetname" "Supply")
    (property "Val" "100n")
    (property "Voltage" "50V")
    (property "ki_description" " ")
    (attr smd)
    (fp_text reference "C149" (at 1.699328 0.412008 180) (layer "F.SilkS")
        (effects (font (size 0.7 0.7) (thickness 0.15)) (justify left bottom))
    )
    (fp_text value "C_100n_0402" (at 0 1.4 180) (layer "F.Fab") hide
        (effects (font (size 0.7 0.7) (thickness 0.15)) (justify left bottom))
    )
    (fp_text user "License: Apache-2.0" (at -0.932 5.17 180) (layer "F.Fab") hide
        (effects (font (size 0.7 0.7) (thickness 0.15)) (justify left bottom))
    )
    (fp_text user "${REFERENCE}" (at -0.932 3.168 180) (layer "F.Fab") hide
        (effects (font (size 0.7 0.7) (thickness 0.15)) (justify left bottom))
    )
    (fp_text user "Author: Antmicro" (at -0.932 4.17 180) (layer "F.Fab") hide
        (effects (font (size 0.7 0.7) (thickness 0.15)) (justify left bottom))
    )
    (fp_rect (start -0.94 -0.47) (end 0.94 0.47)
      (stroke (width 0.05) (type solid)) (fill none) (layer "F.CrtYd"))
    (fp_rect (start -0.499 -0.249) (end 0.499 0.249)
      (stroke (width 0.15) (type solid)) (fill none) (layer "F.Fab"))
    (pad "1" smd roundrect (at -0.484 0 180) (size 0.59 0.64) (layers "F.Cu" "F.Paste" "F.Mask") (roundrect_rratio 0.25)
      (net 7 "Net-(U5-BST)") (pintype "passive"))
    (pad "2" smd roundrect (at 0.484 0 180) (size 0.59 0.64) (layers "F.Cu" "F.Paste" "F.Mask") (roundrect_rratio 0.25)
      (net 8 "Net-(U5-SW)") (pintype "passive"))
  )
)
